G04*
G04 #@! TF.GenerationSoftware,Altium Limited,Altium Designer,22.4.2 (48)*
G04*
G04 Layer_Color=8388736*
%FSLAX25Y25*%
%MOIN*%
G70*
G04*
G04 #@! TF.SameCoordinates,446674BB-F454-490D-8607-5140536C8ADF*
G04*
G04*
G04 #@! TF.FilePolarity,Positive*
G04*
G01*
G75*
M02*
